2 7
DRAWING NO.
SCALE DWG
DO NOT 
MODEL
NAME
APPD
CKD
DSN
DRN
SHEET
SIGNDESCRIPTION DATE
Wiwynn Corporation
A
B
F
MATERIAL
FINISH
OF
DIM IN  mm
REV
15 16 17141 3 4 5 6 8 9 10 11 12 13 1918 2120
K
J
I
L
M
N
O
C
D
E
H
G
20 2118 19131211109865431 14 17161572
G
H
E
D
C
O
N
M
L
I
J
K
F
B
A
(NO TRACE AT ALL LAYERS)28.00
(NO TRACE AT ALL LAYERS)28.00
(NPTH)10.30 0.10
(NPTH)10.30 0.10
(PAD)(NO TRACE AT ALL LAYERS)7.50
 (NO TRACE AT INNER LAYERS)6.00
 (NPTH)2.55
(NPTH)2.41  (NPTH)2.41
 (NPTH)2.55
(NO TRACE AT INNER LAYERS)6.00
102.00
0.00
150.00
300.00
348.00
396.00
26.33
0.00
166.33
323.68
463.68
32.33
20.33
160.33
172.33
329.68
317.68
469.68
457.68
13.20
0.00
5.20
9.20 9.20
5.20
13.20 13.20
9.20
5.20
13.20
5.20
9.20
5.50
120.50
210.80 210.80
6.50
143.50
120.50
5.50
2-3.85
2-229.85
2-247.85
2-481.25
(NPTH)2.20
 (PAD) (NO TRACE AT ALL LAYERS EXCEPT GND)9.50
(PTH)5.70
(NPTH)2.20
127.83
425.18
6- (PAD)(NO TRACE AT ALL LAYERS)9.50
6.50
143.50
20.00
14.00
(PTH)4.20
6- (PTH)3.55
4- (NPTH)2.80
2-44.00
2-170.20
2-341.30
404.40
2-467.50
107.10
3-96.33
3-159.33
3-330.68
3-393.68
202.30202.30
300.20 300.20
244.20 244.20
300.20
310.00
295.70
14.15
6.00
11.00
(PTH)5.30
280.55
414.22
(PTH)3.50
(PAD)(NO TRACE AT ALL LAYERS EXCEPT GND)7.50
(PTH)4.20
(PTH)3.00
(PTH)4.20
(PAD)(NO TRACE AT ALL LAYERS)7.50
(PAD)(NO TRACE AT ALL LAYERS)7.50
(PAD)(NO TRACE AT ALL LAYERS)7.50
(PAD)(NO TRACE AT ALL LAYERS)7.50
(PAD)(NO TRACE AT ALL LAYERS)7.50
(PAD)(NO TRACE AT ALL LAYERS)7.50
(PAD)(NO TRACE AT ALL LAYERS)7.50
224.20
204.20
8.00
483.45
(PTH)4.20
(PTH)4.20
(NO TRACE AT ALL LAYERS)28.00
(NO TRACE AT ALL LAYERS)28.00
6.20
4.20
3.00
5.00
240.00
14.15
6.00
19.00
13.00
(PTH)5.30
11.00
(PAD)(NO TRACE AT ALL LAYERS)7.50
(PAD)(NO TRACE AT ALL LAYERS)7.50
(PAD)(NO TRACE AT ALL LAYERS)7.50
(PAD)(NO TRACE AT ALL LAYERS)7.50
(PAD)(NO TRACE AT ALL LAYERS)7.50
(PAD)(NO TRACE AT ALL LAYERS)7.50
(PAD)(NO TRACE AT ALL LAYERS)7.50
(PAD)(NO TRACE AT ALL LAYERS)7.50
220.00
6-98.80
0.00
6-213.80
6-328.80
349.20
421.20
200.00
366.20
399.20
279.20
189.80
249.20
144.20
69.80
11.80
4-270.00
4-283.00
2-290.00
38.80
374.00
3-33.33
3-456.68
190.70
373.00
491.45
42.75
407.10
164.20 164.20 164.20 164.20
(NO TRACE AT ALL LAYERS)7.50
(NO TRACE AT ALL LAYERS)7.50
(NO TRACE AT ALL LAYERS)7.50
(NO TRACE AT ALL LAYERS)7.50
(PTH)4.20 (PTH)4.20 (PTH)4.20
(PTH)4.20
(NO TRACE AT ALL LAYERS)7.50
(NO TRACE AT ALL LAYERS)7.50
(PAD)6.50
(PAD)6.50
(PAD)6.50(PAD)6.50(PAD)6.50(PAD)6.50
(PAD)6.50
(PAD)6.50 (PAD)6.50
(PAD)6.50
(PAD)6.50
(PAD)6.50
(PTH)4.20
(PAD)6.50
(NO TRACE AT ALL LAYERS)7.50
(PTH)4.20
(PAD)6.50
(NO TRACE AT ALL LAYERS)7.50
182.40
371.60
208.50
220.20
(PAD)6.50
(PAD)6.50
BryceCanyon Bryce Canyon F.DPB
CD 
Jess Wang 6/6
2017
 Jess Wang  6/6
2017
TU863+VLP / NPG170D+VLP T=2.36mm 
1 1  Lenny Kao 
 Lenny Kao  
6/6
2017
6/6
2017
16315-1 VERSION B 2017-06-07
16315-1 VERSION A 2017-06-06
SEE DETAIL A
SEE DETAIL A
SEE DETAIL A
SEE DETAIL F
SEE DETAIL F
COMPONENT SIDE
SOLDER SIDE
SEE DETAIL  A
SEE DETAIL  C
Q'TY:25
SEE DETAIL  F
SEE DETAIL  G
SEE DETAIL  D
SMT NUT(087.71242.0465)
SMT NUT(087.71242.0465)
SMT NUT(087.71242.0465)
SMT NUT(087.71242.0465)
SMT NUT(087.71242.0465)
SMT NUT(087.71242.0465)
SMT NUT(087.71242.0465)
SMT NUT(087.71242.0465)
PRESS FIT THUMB SCREW(086.000IZ.0543) PRESS FIT THUMB SCREW(086.000IZ.0543)
DETAIL  A
SCALE  3.000 DETAIL  C
SCALE  3.000
(NO TRACE AT ALL LAYERS EXCEPT GND)
DETAIL  F
SCALE  3.000
PTH
DETAIL  G
SCALE  3.000
PTH
DETAIL  D
SCALE  3.000
(PAD)(NO TRACE AT ALL LAYERS)